# S9S_MB_2U (Grand Teton) — schematic netlist excerpt (pin names and nets, part order shuffled) for the footprints in the layout excerpt that follows; sources: Cadence DE-HDL packaged netlist, KiCad conversion of 03242023_DA0F0TMBIJ0_F0T_Motherboard_J_brd_V01_OCP.brd

R3165  Q_RES  10K 1% CHIP  pkg 0402LF  page 159 : A = GND ; B = OCP_V3_2_MAIN_PWR_EN
R282  Q_RES  240 1% CHIP  pkg 0402LF  page 119 : A = PVNN_TERM_CPU0 ; B = PU_CPU0_LEGACY_SKT

(kicad_pcb
	(version 20260206)
	(generator "pcbnew")
	(generator_version "10.0")
	(general
		(thickness 1.6)
		(legacy_teardrops no)
	)
	(paper "A4")
	(title_block
		(title "03242023_DA0F0TMBIJ0_F0T_Motherboard_J_brd_V01_OCP.brd")
		(comment 1 "Grand Teton / footprints 5100-5101 of 6105")
	)
	(layers
		(0 "F.Cu" signal "TOP")
		(4 "In1.Cu" signal "GND")
		(6 "In2.Cu" signal "IN1")
		(8 "In3.Cu" signal "GND1")
		(10 "In4.Cu" signal "IN2")
		(12 "In5.Cu" signal "GND2")
		(14 "In6.Cu" signal "IN3")
		(16 "In7.Cu" signal "GND3")
		(18 "In8.Cu" signal "VCC")
		(20 "In9.Cu" signal "VCC1")
		(22 "In10.Cu" signal "GND4")
		(24 "In11.Cu" signal "IN4")
		(26 "In12.Cu" signal "GND5")
		(28 "In13.Cu" signal "IN5")
		(30 "In14.Cu" signal "GND6")
		(32 "In15.Cu" signal "IN6")
		(34 "In16.Cu" signal "GND7")
		(2 "B.Cu" signal "BOTTOM")
		(9 "F.Adhes" user "F.Adhesive")
		(11 "B.Adhes" user "B.Adhesive")
		(13 "F.Paste" user "Package Geometry/Pastemask Top")
		(15 "B.Paste" user "Package Geometry/Pastemask Bottom")
		(5 "F.SilkS" user "Ref Des/Silkscreen Top")
		(7 "B.SilkS" user "Ref Des/Silkscreen Bottom")
		(1 "F.Mask" user "Board Geometry/Soldermask Top")
		(3 "B.Mask" user "Board Geometry/Soldermask Bottom")
		(17 "Dwgs.User" user "User.Drawings")
		(19 "Cmts.User" user "User.Comments")
		(21 "Eco1.User" user "User.Eco1")
		(23 "Eco2.User" user "User.Eco2")
		(25 "Edge.Cuts" user "Board Geometry/Outline")
		(27 "Margin" user)
		(31 "F.CrtYd" user "Package Geometry/Place Bound Top")
		(29 "B.CrtYd" user "Package Geometry/Place Bound Bottom")
		(35 "F.Fab" user "Ref Des/Assembly Top")
		(33 "B.Fab" user "Ref Des/Assembly Bottom")
	)
	(footprint ""
		(layer "B.Cu")
		(at 407.108152 -193.08953 -90)
		(property "Reference" "R282"
			(at 0 0 90)
			(layer "B.SilkS")
			(hide yes)
			(effects
				(font
					(size 1.27 1.27)
				)
				(justify mirror)
			)
		)
		(property "Value" ""
			(at 0 0 90)
			(layer "B.Fab")
			(effects
				(font
					(size 1.27 1.27)
				)
				(justify mirror)
			)
		)
		(duplicate_pad_numbers_are_jumpers no)
		(fp_line
			(start -0.7874 0.4064)
			(end 0.7874 0.4064)
			(stroke
				(width 0.1524)
				(type default)
			)
			(layer "B.SilkS")
		)
		(fp_line
			(start 0.7874 0.4064)
			(end 0.7874 -0.4064)
			(stroke
				(width 0.1524)
				(type default)
			)
			(layer "B.SilkS")
		)
		(fp_line
			(start -0.7874 -0.4064)
			(end -0.7874 0.4064)
			(stroke
				(width 0.1524)
				(type default)
			)
			(layer "B.SilkS")
		)
		(fp_line
			(start 0.7874 -0.4064)
			(end -0.7874 -0.4064)
			(stroke
				(width 0.1524)
				(type default)
			)
			(layer "B.SilkS")
		)
		(fp_line
			(start -0.67945 0.3048)
			(end -0.120396 0.3048)
			(stroke
				(width 0.1)
				(type default)
			)
			(layer "B.Fab")
		)
		(fp_line
			(start -0.120396 0.3048)
			(end -0.120396 0.2794)
			(stroke
				(width 0.1)
				(type default)
			)
			(layer "B.Fab")
		)
		(fp_line
			(start 0.12065 0.3048)
			(end 0.67945 0.3048)
			(stroke
				(width 0.1)
				(type default)
			)
			(layer "B.Fab")
		)
		(fp_line
			(start 0.67945 0.3048)
			(end 0.67945 -0.305054)
			(stroke
				(width 0.1)
				(type default)
			)
			(layer "B.Fab")
		)
		(fp_line
			(start -0.120396 0.2794)
			(end 0.12065 0.2794)
			(stroke
				(width 0.1)
				(type default)
			)
			(layer "B.Fab")
		)
		(fp_line
			(start 0.12065 0.2794)
			(end 0.12065 0.3048)
			(stroke
				(width 0.1)
				(type default)
			)
			(layer "B.Fab")
		)
		(fp_line
			(start -0.12065 -0.2794)
			(end -0.12065 -0.3048)
			(stroke
				(width 0.1)
				(type default)
			)
			(layer "B.Fab")
		)
		(fp_line
			(start 0.12065 -0.2794)
			(end -0.12065 -0.2794)
			(stroke
				(width 0.1)
				(type default)
			)
			(layer "B.Fab")
		)
		(fp_line
			(start -0.67945 -0.3048)
			(end -0.67945 0.3048)
			(stroke
				(width 0.1)
				(type default)
			)
			(layer "B.Fab")
		)
		(fp_line
			(start -0.12065 -0.3048)
			(end -0.67945 -0.3048)
			(stroke
				(width 0.1)
				(type default)
			)
			(layer "B.Fab")
		)
		(fp_line
			(start 0.12065 -0.305054)
			(end 0.12065 -0.2794)
			(stroke
				(width 0.1)
				(type default)
			)
			(layer "B.Fab")
		)
		(fp_line
			(start 0.67945 -0.305054)
			(end 0.12065 -0.305054)
			(stroke
				(width 0.1)
				(type default)
			)
			(layer "B.Fab")
		)
		(pad "1" smd circle
			(at 0.40005 0 90)
			(size 0 0)
			(layers "B.Cu" "B.Mask" "B.Paste")
			(net "PVNN_TERM_CPU0")
		)
		(pad "2" smd circle
			(at -0.40005 0 90)
			(size 0 0)
			(layers "B.Cu" "B.Mask" "B.Paste")
			(net "PU_CPU0_LEGACY_SKT")
		)
	)
	(footprint ""
		(layer "B.Cu")
		(at 75.87488 -11.267948 -90)
		(property "Reference" "R3165"
			(at 0 0 90)
			(layer "B.SilkS")
			(hide yes)
			(effects
				(font
					(size 1.27 1.27)
				)
				(justify mirror)
			)
		)
		(property "Value" ""
			(at 0 0 90)
			(layer "B.Fab")
			(effects
				(font
					(size 1.27 1.27)
				)
				(justify mirror)
			)
		)
		(duplicate_pad_numbers_are_jumpers no)
		(fp_line
			(start -0.7874 0.4064)
			(end 0.7874 0.4064)
			(stroke
				(width 0.1524)
				(type default)
			)
			(layer "B.SilkS")
		)
		(fp_line
			(start 0.7874 0.4064)
			(end 0.7874 -0.4064)
			(stroke
				(width 0.1524)
				(type default)
			)
			(layer "B.SilkS")
		)
		(fp_line
			(start -0.7874 -0.4064)
			(end -0.7874 0.4064)
			(stroke
				(width 0.1524)
				(type default)
			)
			(layer "B.SilkS")
		)
		(fp_line
			(start 0.7874 -0.4064)
			(end -0.7874 -0.4064)
			(stroke
				(width 0.1524)
				(type default)
			)
			(layer "B.SilkS")
		)
		(fp_line
			(start -0.67945 0.3048)
			(end -0.120396 0.3048)
			(stroke
				(width 0.1)
				(type default)
			)
			(layer "B.Fab")
		)
		(fp_line
			(start -0.120396 0.3048)
			(end -0.120396 0.2794)
			(stroke
				(width 0.1)
				(type default)
			)
			(layer "B.Fab")
		)
		(fp_line
			(start 0.12065 0.3048)
			(end 0.67945 0.3048)
			(stroke
				(width 0.1)
				(type default)
			)
			(layer "B.Fab")
		)
		(fp_line
			(start 0.67945 0.3048)
			(end 0.67945 -0.305054)
			(stroke
				(width 0.1)
				(type default)
			)
			(layer "B.Fab")
		)
		(fp_line
			(start -0.120396 0.2794)
			(end 0.12065 0.2794)
			(stroke
				(width 0.1)
				(type default)
			)
			(layer "B.Fab")
		)
		(fp_line
			(start 0.12065 0.2794)
			(end 0.12065 0.3048)
			(stroke
				(width 0.1)
				(type default)
			)
			(layer "B.Fab")
		)
		(fp_line
			(start -0.12065 -0.2794)
			(end -0.12065 -0.3048)
			(stroke
				(width 0.1)
				(type default)
			)
			(layer "B.Fab")
		)
		(fp_line
			(start 0.12065 -0.2794)
			(end -0.12065 -0.2794)
			(stroke
				(width 0.1)
				(type default)
			)
			(layer "B.Fab")
		)
		(fp_line
			(start -0.67945 -0.3048)
			(end -0.67945 0.3048)
			(stroke
				(width 0.1)
				(type default)
			)
			(layer "B.Fab")
		)
		(fp_line
			(start -0.12065 -0.3048)
			(end -0.67945 -0.3048)
			(stroke
				(width 0.1)
				(type default)
			)
			(layer "B.Fab")
		)
		(fp_line
			(start 0.12065 -0.305054)
			(end 0.12065 -0.2794)
			(stroke
				(width 0.1)
				(type default)
			)
			(layer "B.Fab")
		)
		(fp_line
			(start 0.67945 -0.305054)
			(end 0.12065 -0.305054)
			(stroke
				(width 0.1)
				(type default)
			)
			(layer "B.Fab")
		)
		(pad "1" smd circle
			(at 0.40005 0 90)
			(size 0 0)
			(layers "B.Cu" "B.Mask" "B.Paste")
			(net "GND")
		)
		(pad "2" smd circle
			(at -0.40005 0 90)
			(size 0 0)
			(layers "B.Cu" "B.Mask" "B.Paste")
			(net "OCP_V3_2_MAIN_PWR_EN")
		)
	)
)
